# S9S_MB_2U (Grand Teton) — schematic parts with pin connectivity, parts 5880–5880 of 6093; source: Cadence DE-HDL packaged netlist (pstxprt.dat, pstxnet.dat, pstchip.dat)

U2  SOCKET4677_AZIF0045P001C01CS  SOCKET4677_AZIF0045-P001C01CS IO  pkg SOCKET4677_82X64-5XA_H466  page 13  (pins 1631-1956 of 4677)
  BY83  VCCIN221  POWER  = PVCCIN_CPU0
  BY85  VCCIN222  POWER  = PVCCIN_CPU0
  BY87  VCCIN223  POWER  = PVCCIN_CPU0
  BY89  VCCIN224  POWER  = PVCCIN_CPU0
  C5  VSS612  POWER  = GND
  C7  DDR0_SB_DQ29  BI  = M_A_CPU0_SB_DQ<29>
  C9  DDR0_SB_DQS_DP3  BI  = M_A_CPU0_SB_DQS_DP<3>
  C11  DDR0_SB_DQ24  BI  = M_A_CPU0_SB_DQ<24>
  C13  DDR1_SB_DQ28  BI  = M_B_CPU0_SB_DQ<28>
  C15  DDR1_SB_DQS_DP3  BI  = M_B_CPU0_SB_DQS_DP<3>
  C17  DDR1_SB_DQ24  BI  = M_B_CPU0_SB_DQ<24>
  C19  DDR0_SB_DQ21  BI  = M_A_CPU0_SB_DQ<21>
  C21  DDR0_SB_DQS_DP2  BI  = M_A_CPU0_SB_DQS_DP<2>
  C23  DDR0_SB_DQ16  BI  = M_A_CPU0_SB_DQ<16>
  C25  DDR0_SB_DQ13  BI  = M_A_CPU0_SB_DQ<13>
  C27  DDR0_SB_DQS_DP1  BI  = M_A_CPU0_SB_DQS_DP<1>
  C29  DDR0_SB_DQ8  BI  = M_A_CPU0_SB_DQ<8>
  C31  DDR0_SB_ECC1  BI  = M_A_CPU0_SB_CB<1>
  C33  DDR0_SB_DQS_DP9  BI  = M_A_CPU0_SB_DQS_DP<9>
  C35  DDR0_SB_ECC4  BI  = M_A_CPU0_SB_CB<4>
  C37  DDR0_SB_CS_N1  OUT  = M_A_CPU0_SB_CS_N<1>
  C39  VSS609  POWER  = GND
  C41  DDR0_SB_CA2  OUT  = M_A_CPU0_SB_CA<2>
  C43  DDR0_CLK_DP0  OUT  = M_A_CPU0_CLK_DP<0>
  C45  VSS610  POWER  = GND
  C48  DDR0_SA_CA6  OUT  = M_A_CPU0_SA_CA<6>
  C50  DDR0_SA_CA4  OUT  = M_A_CPU0_SA_CA<4>
  C52  VSS613  POWER  = GND
  C54  DDR0_SA_CS_N0  OUT  = M_A_CPU0_SA_CS_N<0>
  C56  DDR0_SA_ECC5  BI  = M_A_CPU0_SA_CB<5>
  C58  DDR0_SA_DQS_DP4  BI  = M_A_CPU0_SA_DQS_DP<4>
  C60  DDR0_SA_ECC0  BI  = M_A_CPU0_SA_CB<0>
  C62  DDR0_SA_DQ29  BI  = M_A_CPU0_SA_DQ<29>
  C64  DDR0_SA_DQS_DP3  BI  = M_A_CPU0_SA_DQS_DP<3>
  C66  DDR0_SA_DQ24  BI  = M_A_CPU0_SA_DQ<24>
  C68  DDR0_SA_DQ21  BI  = M_A_CPU0_SA_DQ<21>
  C70  DDR0_SA_DQS_DP2  BI  = M_A_CPU0_SA_DQS_DP<2>
  C72  VSS614  POWER  = GND
  C74  VSS615  POWER  = GND
  C76  DDR0_SA_DQ4  BI  = M_A_CPU0_SA_DQ<4>
  C78  VSS616  POWER  = GND
  C80  VSS617  POWER  = GND
  C82  VSS618  POWER  = GND
  C84  VCCFA_EHV_FIVRA32  POWER  = PVCCFA_EHV_FIVRA_CPU0
  C86  VSS619  POWER  = GND
  C88  VCCFA_EHV_FIVRA33  POWER  = PVCCFA_EHV_FIVRA_CPU0
  CA3  VSS620  POWER  = GND
  CA5  UPI1_TX_DN22  OUT  = UPI_CPU0_CPU1_P1P0_DN<22>
  CA7  VCCD_HV19  POWER  = PVCCD_HV_CPU0
  CA9  PE1_RX_DP6  IN  = P5E_CPU0_PE1_RX_DP<6>
  CA11  VCCINFAON_SENSE  POWER  = VSENSE_PVCCINFAON_CPU0_DP
  CA13  PE1_TX_DN7  OUT  = P5E_CPU0_PE1_TX_DN<7>
  CA15  VCCINFAON43  POWER  = PVCCINFAON_CPU0
  CA17  DMI_TX_DN1  OUT  = DMI_CPU0_PCH_TX_DP<1>
  CA19  DMI_TX_DP0  OUT  = DMI_CPU0_PCH_TX_DN<0>
  CA21  RSVD77  BI  = NC_CPU0_DMI_APROBE<0>
  CA23  RSVD78  BI  = NC_CPU0_UPI1_APROBE<1>
  CA25  CXPSMBUSSCL  OUT  = SMB_PEHPCPU0_GTL_SCL
  CA27  PTI_DIE006  OUT  = TP_TRC_CPU0_PTI<6>
  CA29  PTI_DIE004  OUT  = TP_TRC_CPU0_PTI<4>
  CA31  VSS621  POWER  = GND
  CA33  VCCIN225  POWER  = PVCCIN_CPU0
  CA35  VCCIN226  POWER  = PVCCIN_CPU0
  CA37  VCCIN227  POWER  = PVCCIN_CPU0
  CA39  VCCIN228  POWER  = PVCCIN_CPU0
  CA41  VCCIN229  POWER  = PVCCIN_CPU0
  CA43  VCCIN230  POWER  = PVCCIN_CPU0
  CA45  VCCIN231  POWER  = PVCCIN_CPU0
  CA48  VCCIN232  POWER  = PVCCIN_CPU0
  CA50  VCCIN233  POWER  = PVCCIN_CPU0
  CA52  VCCIN234  POWER  = PVCCIN_CPU0
  CA54  VCCIN235  POWER  = PVCCIN_CPU0
  CA56  VCCIN236  POWER  = PVCCIN_CPU0
  CA58  VCCIN237  POWER  = PVCCIN_CPU0
  CA60  VCCIN238  POWER  = PVCCIN_CPU0
  CA62  VCCIN239  POWER  = PVCCIN_CPU0
  CA64  VCCIN240  POWER  = PVCCIN_CPU0
  CA66  VCCIN241  POWER  = PVCCIN_CPU0
  CA68  VCCIN242  POWER  = PVCCIN_CPU0
  CA70  VCCIN243  POWER  = PVCCIN_CPU0
  CA72  VCCIN244  POWER  = PVCCIN_CPU0
  CA74  VCCIN245  POWER  = PVCCIN_CPU0
  CA76  VCCIN246  POWER  = PVCCIN_CPU0
  CA78  VCCIN247  POWER  = PVCCIN_CPU0
  CA80  VCCIN248  POWER  = PVCCIN_CPU0
  CA82  VCCIN249  POWER  = PVCCIN_CPU0
  CA84  VCCIN250  POWER  = PVCCIN_CPU0
  CA86  VCCIN251  POWER  = PVCCIN_CPU0
  CA88  VCCIN252  POWER  = PVCCIN_CPU0
  CA90  VCCIN253  POWER  = PVCCIN_CPU0
  CB2  UPI1_RX_DN23  IN  = UPI_CPU1_CPU0_P0P1_DP<23>
  CB4  VSS633  POWER  = GND
  CB6  UPI1_TX_DP22  OUT  = UPI_CPU0_CPU1_P1P0_DP<22>
  CB8  VSS651  POWER  = GND
  CB10  PE1_RX_DN6  IN  = P5E_CPU0_PE1_RX_DN<6>
  CB12  VSS622  POWER  = GND
  CB14  PE1_TX_DN6  OUT  = P5E_CPU0_PE1_TX_DN<6>
  CB16  VSS623  POWER  = GND
  CB18  DMI_TX_DN2  OUT  = DMI_CPU0_PCH_TX_DP<2>
  CB20  VSS624  POWER  = GND
  CB22  VSS625  POWER  = GND
  CB24  VSS626  POWER  = GND
  CB26  VSS627  POWER  = GND
  CB28  VSS628  POWER  = GND
  CB30  PTI_DIE00_STB_0  OUT  = TP_TRC_CPU0_PTI0_CLK
  CB32  VSS629  POWER  = GND
  CB34  VSS630  POWER  = GND
  CB36  VSS631  POWER  = GND
  CB38  VSS632  POWER  = GND
  CB40  VSS634  POWER  = GND
  CB42  VSS635  POWER  = GND
  CB44  VSS636  POWER  = GND
  CB47  VSS637  POWER  = GND
  CB49  VSS638  POWER  = GND
  CB51  VSS639  POWER  = GND
  CB53  VSS640  POWER  = GND
  CB55  VSS641  POWER  = GND
  CB57  VSS642  POWER  = GND
  CB59  VSS643  POWER  = GND
  CB61  VCCIN254  POWER  = PVCCIN_CPU0
  CB63  VSS644  POWER  = GND
  CB65  VSS645  POWER  = GND
  CB67  VSS646  POWER  = GND
  CB69  VSS647  POWER  = GND
  CB71  VSS648  POWER  = GND
  CB73  VSS649  POWER  = GND
  CB75  VCCIN255  POWER  = PVCCIN_CPU0
  CB77  VCCIN256  POWER  = PVCCIN_CPU0
  CB79  VSS650  POWER  = GND
  CB81  VSS652  POWER  = GND
  CB83  VSS653  POWER  = GND
  CB85  VSS654  POWER  = GND
  CB87  VSS655  POWER  = GND
  CB89  VSS656  POWER  = GND
  CC3  UPI1_RX_DP22  IN  = UPI_CPU1_CPU0_P0P1_DN<22>
  CC5  VSS665  POWER  = GND
  CC7  UPI1_TX_DP21  OUT  = UPI_CPU0_CPU1_P1P0_DN<21>
  CC9  VSS670  POWER  = GND
  CC11  PE1_RX_DN5  IN  = P5E_CPU0_PE1_RX_DN<5>
  CC13  VSS660  POWER  = GND
  CC15  PE1_TX_DP6  OUT  = P5E_CPU0_PE1_TX_DP<6>
  CC17  VSS661  POWER  = GND
  CC19  DMI_TX_DP2  OUT  = DMI_CPU0_PCH_TX_DN<2>
  CC21  RSVD79  BI  = NC_CPU0_PE1_APROBE<1>
  CC23  RSVD80  BI  = NC_CPU0_PE2_APROBE<0>
  CC25  PMDOWN6  BI  = TP_H_SBLINK7_CPU0_PMDOWN
  CC27  PTI_DIE002  OUT  = TP_TRC_CPU0_PTI<2>
  CC29  PTI_DIE000  OUT  = TP_TP_TRC_CPU0_PTI_MON<0>
  CC31  VSS664  POWER  = GND
  CC33  VCCIN257  POWER  = PVCCIN_CPU0
  CC35  VCCIN258  POWER  = PVCCIN_CPU0
  CC37  VCCIN259  POWER  = PVCCIN_CPU0
  CC39  VCCIN260  POWER  = PVCCIN_CPU0
  CC41  VCCIN261  POWER  = PVCCIN_CPU0
  CC43  VCCIN262  POWER  = PVCCIN_CPU0
  CC45  VCCIN263  POWER  = PVCCIN_CPU0
  CC48  VCCIN264  POWER  = PVCCIN_CPU0
  CC50  VCCIN265  POWER  = PVCCIN_CPU0
  CC52  VCCIN266  POWER  = PVCCIN_CPU0
  CC54  VCCIN267  POWER  = PVCCIN_CPU0
  CC56  VCCIN268  POWER  = PVCCIN_CPU0
  CC58  VCCIN269  POWER  = PVCCIN_CPU0
  CC60  VCCIN270  POWER  = PVCCIN_CPU0
  CC62  VSS666  POWER  = GND
  CC64  RSVD81  BI  = NC_CPU0_LGSSPARE4
  CC66  RSVD82  BI  = NC_CPU0_MDFI_DIE01_EW1
  CC68  VPP_HBM4  POWER  = PVPP_HBM_CPU0
  CC70  VSS667  POWER  = GND
  CC72  VSS668  POWER  = GND
  CC74  VSS669  POWER  = GND
  CC76  VCCIN271  POWER  = PVCCIN_CPU0
  CC78  VCCIN272  POWER  = PVCCIN_CPU0
  CC80  VCCIN273  POWER  = PVCCIN_CPU0
  CC82  VCCIN274  POWER  = PVCCIN_CPU0
  CC84  VCCIN275  POWER  = PVCCIN_CPU0
  CC86  VCCIN276  POWER  = PVCCIN_CPU0
  CC88  VCCIN277  POWER  = PVCCIN_CPU0
  CC90  VCCIN278  POWER  = PVCCIN_CPU0
  CD2  UPI1_RX_DN22  IN  = UPI_CPU1_CPU0_P0P1_DP<22>
  CD4  VSS674  POWER  = GND
  CD6  UPI1_TX_DN21  OUT  = UPI_CPU0_CPU1_P1P0_DP<21>
  CD8  VSS678  POWER  = GND
  CD10  PE1_RX_DP5  IN  = P5E_CPU0_PE1_RX_DP<5>
  CD12  VSS671  POWER  = GND
  CD14  PE1_TX_DP5  OUT  = P5E_CPU0_PE1_TX_DP<5>
  CD16  VSS672  POWER  = GND
  CD18  DMI_TX_DP3  OUT  = DMI_CPU0_PCH_TX_DN<3>
  CD20  VSS673  POWER  = GND
  CD22  RSVD83  BI  = NC_CPU0_MDFI_DIE10_NS1
  CD24  PMDOWN3  BI  = TP_H_SBLINK4_CPU0_PMDOWN
  CD26  RSVD84  BI  = NC_CPU0_MDFI_DIE10_EW0
  CD28  PTI_DIE001  OUT  = TP_TRC_CPU0_PTI_MON<1>
  CD30  RSVD85  BI  = NC_CPU0_MDFI_DIE10_EW1
  CD32  VCCIN279  POWER  = PVCCIN_CPU0
  CD34  VCCIN280  POWER  = PVCCIN_CPU0
  CD36  VCCIN281  POWER  = PVCCIN_CPU0
  CD38  VCCIN282  POWER  = PVCCIN_CPU0
  CD40  VCCIN283  POWER  = PVCCIN_CPU0
  CD42  VCCIN284  POWER  = PVCCIN_CPU0
  CD44  VCCIN285  POWER  = PVCCIN_CPU0
  CD47  VCCIN286  POWER  = PVCCIN_CPU0
  CD49  VCCIN287  POWER  = PVCCIN_CPU0
  CD51  VCCIN288  POWER  = PVCCIN_CPU0
  CD53  VCCIN289  POWER  = PVCCIN_CPU0
  CD55  VCCIN290  POWER  = PVCCIN_CPU0
  CD57  VCCIN291  POWER  = PVCCIN_CPU0
  CD59  VCCIN292  POWER  = PVCCIN_CPU0
  CD61  VSS675  POWER  = GND
  CD63  SMB_DATA  BI  = SMB_S3M_CPU0_SDA
  CD65  RSVD86  BI  = TP_SGPIO_S3M_CPU0_RST_R_N
  CD67  VPP_HBM3  POWER  = PVPP_HBM_CPU0
  CD69  RSVD87  BI  = TP_CPU0_SPARE11
  CD71  RSVD88  BI  = NC_CLK_PFT_OUT_CPU0_DP
  CD73  UPI3_TX_DP23  OUT  = NC
  CD75  VSS676  POWER  = GND
  CD77  VSS677  POWER  = GND
  CD79  VCCIN293  POWER  = PVCCIN_CPU0
  CD81  VCCIN294  POWER  = PVCCIN_CPU0
  CD83  VCCIN295  POWER  = PVCCIN_CPU0
  CD85  VCCIN296  POWER  = PVCCIN_CPU0
  CD87  VCCIN297  POWER  = PVCCIN_CPU0
  CD89  VCCIN298  POWER  = PVCCIN_CPU0
  CE1  UPI1_RX_DP21  IN  = UPI_CPU1_CPU0_P0P1_DP<21>
  CE3  VSS680  POWER  = GND
  CE5  UPI1_TX_DN20  OUT  = UPI_CPU0_CPU1_P1P0_DP<20>
  CE7  VCCD_HV20  POWER  = PVCCD_HV_CPU0
  CE9  PE1_RX_DP4  IN  = P5E_CPU0_PE1_RX_DP<4>
  CE11  VSS_VCCINFAON_SENSE  POWER  = VSENSE_PVCCINFAON_CPU0_DN
  CE13  PE1_TX_DN5  OUT  = P5E_CPU0_PE1_TX_DN<5>
  CE15  VCCINFAON0  POWER  = PVCCINFAON_CPU0
  CE17  DMI_TX_DN3  OUT  = DMI_CPU0_PCH_TX_DP<3>
  CE19  VCCINFAON44  POWER  = PVCCINFAON_CPU0
  CE21  RSVD89  BI  = NC_CPU0_PE1_APROBE<0>
  CE23  PMDOWN5  BI  = TP_H_SBLINK6_CPU0_PMDOWN
  CE25  PMSYNC3  BI  = TP_H_SBLINK4_CPU0_PMSYNC
  CE60  VSS681  POWER  = GND
  CE62  RSVD90  BI  = NC_CPU0_LGSSPARE3
  CE64  SMB_CLK  OUT  = SMB_S3M_CPU0_SCL
  CE66  VSS682  POWER  = GND
  CE68  VPP_HBM2  POWER  = PVPP_HBM_CPU0
  CE70  RSVD91  BI  = NC_CLK_PFT_OUT_CPU0_DN
  CE72  VSS683  POWER  = GND
  CE74  VCCFA_EHV_FIVRA34  POWER  = PVCCFA_EHV_FIVRA_CPU0
  CE76  VSS684  POWER  = GND
  CE78  VSS685  POWER  = GND
  CE80  VCCIN299  POWER  = PVCCIN_CPU0
  CE82  VCCIN300  POWER  = PVCCIN_CPU0
  CE84  VCCIN301  POWER  = PVCCIN_CPU0
  CE86  VCCIN302  POWER  = PVCCIN_CPU0
  CE88  VCCIN303  POWER  = PVCCIN_CPU0
  CE90  VCCIN304  POWER  = PVCCIN_CPU0
  CF2  UPI1_RX_DN21  IN  = UPI_CPU1_CPU0_P0P1_DN<21>
  CF4  VSS689  POWER  = GND
  CF6  UPI1_TX_DP20  OUT  = UPI_CPU0_CPU1_P1P0_DN<20>
  CF8  VSS693  POWER  = GND
  CF10  PE1_RX_DN4  IN  = P5E_CPU0_PE1_RX_DN<4>
  CF12  VSS686  POWER  = GND
  CF14  PE1_TX_DN4  OUT  = P5E_CPU0_PE1_TX_DN<4>
  CF16  VSS687  POWER  = GND
  CF18  DMI_TX_DN4  OUT  = DMI_CPU0_PCH_TX_DN<4>
  CF20  VSS688  POWER  = GND
  CF22  RSVD92  BI  = NC_CPU0_MDFI_DIE10_NS0
  CF24  PMSYNC6  BI  = TP_H_SBLINK7_CPU0_PMSYNC
  CF26  MEMHOT_OUT_N  OUT  = H_CPU0_MEMHOT_OUT_LVC1_R_N
  CF61  TEST_6  BI  = PUD_PCH_BOOT_MODE_CPU0
  CF63  RSVD93  BI  = TP_SGPIO_S3M_CPU0_GSXCLK_R
  CF65  RSVD94  BI  = TP_SGPIO_S3M_CPU0_GSXDOUT_R
  CF67  VPP_HBM1  POWER  = PVPP_HBM_CPU0
  CF69  VSS691  POWER  = GND
  CF71  VSS692  POWER  = GND
  CF73  UPI3_TX_DN23  OUT  = NC
  CF75  UPI3_TX_DN20  OUT  = NC
  CF77  UPI3_TX_DP19  OUT  = NC
  CF79  VCCIN305  POWER  = PVCCIN_CPU0
  CF81  VCCIN306  POWER  = PVCCIN_CPU0
  CF83  VCCIN307  POWER  = PVCCIN_CPU0
  CF85  VCCIN308  POWER  = PVCCIN_CPU0
  CF87  VCCIN309  POWER  = PVCCIN_CPU0
  CF89  VCCIN310  POWER  = PVCCIN_CPU0
  CF91  VCCIN311  POWER  = PVCCIN_CPU0
  CG1  VSS694  POWER  = GND
  CG3  UPI1_RX_DP20  IN  = UPI_CPU1_CPU0_P0P1_DN<20>
  CG5  VSS703  POWER  = GND
  CG7  UPI1_TX_DP19  OUT  = UPI_CPU0_CPU1_P1P0_DN<19>
  CG9  VSS716  POWER  = GND
  CG11  PE1_RX_DN3  IN  = P5E_CPU0_PE1_RX_DN<3>
  CG13  VSS695  POWER  = GND
  CG15  PE1_TX_DP4  OUT  = P5E_CPU0_PE1_TX_DP<4>
  CG17  VSS696  POWER  = GND
  CG19  DMI_TX_DP4  OUT  = DMI_CPU0_PCH_TX_DP<4>
  CG21  VSS697  POWER  = GND
  CG23  VSS698  POWER  = GND
  CG25  VSS701  POWER  = GND
  CG60  RSVD95  BI  = TP_CPU0_SPARE10
  CG62  VSS704  POWER  = GND
  CG64  VSS706  POWER  = GND
  CG66  SKTOCC_N  OUT  = FM_CPU0_SKTOCC_LVT3_N
  CG68  VPP_HBM  POWER  = PVPP_HBM_CPU0
  CG70  VSS707  POWER  = GND
  CG72  VSS708  POWER  = GND
  CG74  VSS710  POWER  = GND
  CG76  UPI3_TX_DN19  OUT  = NC
  CG78  VSS713  POWER  = GND
  CG80  VCCIN312  POWER  = PVCCIN_CPU0
  CG82  VCCIN313  POWER  = PVCCIN_CPU0
  CG84  VCCIN314  POWER  = PVCCIN_CPU0
  CG86  VCCIN315  POWER  = PVCCIN_CPU0
  CG88  VCCIN316  POWER  = PVCCIN_CPU0
  CG90  VCCIN317  POWER  = PVCCIN_CPU0
  CH2  UPI1_RX_DN20  IN  = UPI_CPU1_CPU0_P0P1_DP<20>
  CH4  VSS722  POWER  = GND
  CH6  UPI1_TX_DN19  OUT  = UPI_CPU0_CPU1_P1P0_DP<19>
  CH8  VSS730  POWER  = GND
  CH10  PE1_RX_DP3  IN  = P5E_CPU0_PE1_RX_DP<3>
  CH12  VSS718  POWER  = GND
  CH14  PE1_TX_DP3  OUT  = P5E_CPU0_PE1_TX_DP<3>
  CH16  VSS720  POWER  = GND
  CH18  DMI_TX_DP5  OUT  = DMI_CPU0_PCH_TX_DP<5>
  CH20  VSS721  POWER  = GND
  CH22  RSVD96  BI  = PD_CPU0_ENH_MCECC_DIS
  CH24  PMSYNC5  BI  = TP_H_SBLINK6_CPU0_PMSYNC
  CH26  PMSYNC2  BI  = TP_H_SBLINK3_CPU0_PMSYNC
  CH61  RSVD97  BI  = TP_CPU0_SPARE9
  CH63  RSVD98  BI  = TP_SGPIO_S3M_CPU0_GSXDIN
  CH65  TEST_3  BI  = PU_S3M_CPU0_CPLD_STATUS
  CH67  VSS727  POWER  = GND
